(kicad_pcb
	(version 20260206)
	(generator "pcbnew")
	(generator_version "10.0")
	(general
		(thickness 1.6)
		(legacy_teardrops no)
	)
	(paper "A4")
	(title_block
		(title "03242023_DA0F0TMBIJ0_F0T_Motherboard_J_brd_V01_OCP.brd")
		(comment 1 "Grand Teton / footprints 2720-2726 of 6105")
	)
	(layers
		(0 "F.Cu" signal "TOP")
		(4 "In1.Cu" signal "GND")
		(6 "In2.Cu" signal "IN1")
		(8 "In3.Cu" signal "GND1")
		(10 "In4.Cu" signal "IN2")
		(12 "In5.Cu" signal "GND2")
		(14 "In6.Cu" signal "IN3")
		(16 "In7.Cu" signal "GND3")
		(18 "In8.Cu" signal "VCC")
		(20 "In9.Cu" signal "VCC1")
		(22 "In10.Cu" signal "GND4")
		(24 "In11.Cu" signal "IN4")
		(26 "In12.Cu" signal "GND5")
		(28 "In13.Cu" signal "IN5")
		(30 "In14.Cu" signal "GND6")
		(32 "In15.Cu" signal "IN6")
		(34 "In16.Cu" signal "GND7")
		(2 "B.Cu" signal "BOTTOM")
		(9 "F.Adhes" user "F.Adhesive")
		(11 "B.Adhes" user "B.Adhesive")
		(13 "F.Paste" user "Package Geometry/Pastemask Top")
		(15 "B.Paste" user "Package Geometry/Pastemask Bottom")
		(5 "F.SilkS" user "Ref Des/Silkscreen Top")
		(7 "B.SilkS" user "Ref Des/Silkscreen Bottom")
		(1 "F.Mask" user "Board Geometry/Soldermask Top")
		(3 "B.Mask" user "Board Geometry/Soldermask Bottom")
		(17 "Dwgs.User" user "User.Drawings")
		(19 "Cmts.User" user "User.Comments")
		(21 "Eco1.User" user "User.Eco1")
		(23 "Eco2.User" user "User.Eco2")
		(25 "Edge.Cuts" user "Board Geometry/Outline")
		(27 "Margin" user)
		(31 "F.CrtYd" user "Package Geometry/Place Bound Top")
		(29 "B.CrtYd" user "Package Geometry/Place Bound Bottom")
		(35 "F.Fab" user "Ref Des/Assembly Top")
		(33 "B.Fab" user "Ref Des/Assembly Bottom")
	)
	(footprint ""
		(layer "F.Cu")
		(at 196.67982 -80.617568)
		(property "Reference" "D6"
			(at -1.397 -1.24333 0)
			(unlocked yes)
			(layer "F.SilkS")
			(effects
				(font
					(size 0.7874 0.5842)
					(thickness 0.1524)
				)
				(justify left)
			)
		)
		(property "Value" ""
			(at 0 0 0)
			(layer "F.Fab")
			(effects
				(font
					(size 1.27 1.27)
				)
			)
		)
		(duplicate_pad_numbers_are_jumpers no)
		(fp_line
			(start -1.3208 -0.5588)
			(end 1.3208 -0.5588)
			(stroke
				(width 0.1524)
				(type default)
			)
			(layer "F.SilkS")
		)
		(fp_line
			(start -1.3208 0.5588)
			(end -1.3208 -0.5588)
			(stroke
				(width 0.1524)
				(type default)
			)
			(layer "F.SilkS")
		)
		(fp_line
			(start 1.3208 -0.5588)
			(end 1.3208 0.5588)
			(stroke
				(width 0.1524)
				(type default)
			)
			(layer "F.SilkS")
		)
		(fp_line
			(start 1.3208 0.5588)
			(end -1.3208 0.5588)
			(stroke
				(width 0.1524)
				(type default)
			)
			(layer "F.SilkS")
		)
		(fp_line
			(start 1.4732 -0.5588)
			(end 1.4732 0.5588)
			(stroke
				(width 0.1524)
				(type default)
			)
			(layer "F.SilkS")
		)
		(fp_line
			(start 1.6256 0.5588)
			(end 1.6256 -0.5588)
			(stroke
				(width 0.1524)
				(type default)
			)
			(layer "F.SilkS")
		)
		(fp_line
			(start 1.778 -0.5588)
			(end 1.3208 -0.5588)
			(stroke
				(width 0.1524)
				(type default)
			)
			(layer "F.SilkS")
		)
		(fp_line
			(start 1.778 -0.5588)
			(end 1.778 0.5588)
			(stroke
				(width 0.1524)
				(type default)
			)
			(layer "F.SilkS")
		)
		(fp_line
			(start 1.778 0.5588)
			(end 1.3208 0.5588)
			(stroke
				(width 0.1524)
				(type default)
			)
			(layer "F.SilkS")
		)
		(fp_line
			(start -0.899922 -0.40005)
			(end 0.899922 -0.40005)
			(stroke
				(width 0.1)
				(type default)
			)
			(layer "F.Fab")
		)
		(fp_line
			(start -0.899922 0.40005)
			(end -0.899922 -0.40005)
			(stroke
				(width 0.1)
				(type default)
			)
			(layer "F.Fab")
		)
		(fp_line
			(start 0.899922 -0.40005)
			(end 0.899922 0.40005)
			(stroke
				(width 0.1)
				(type default)
			)
			(layer "F.Fab")
		)
		(fp_line
			(start 0.899922 0.40005)
			(end -0.899922 0.40005)
			(stroke
				(width 0.1)
				(type default)
			)
			(layer "F.Fab")
		)
		(fp_text user "+"
			(at -2.8956 -1.23825 0)
			(unlocked yes)
			(layer "F.SilkS")
			(effects
				(font
					(size 1.905 1.4224)
					(thickness 0.1524)
				)
				(justify left)
			)
		)
		(fp_text user "-"
			(at 1.651 -0.22225 0)
			(unlocked yes)
			(layer "F.SilkS")
			(effects
				(font
					(size 1.905 1.4224)
					(thickness 0.1524)
				)
				(justify left)
			)
		)
		(fp_text user "+"
			(at -2.6162 -0.22225 0)
			(unlocked yes)
			(layer "F.Fab")
			(effects
				(font
					(size 1.905 1.4224)
					(thickness 0.1524)
				)
				(justify left)
			)
		)
		(fp_text user "-"
			(at 1.651 -0.22225 0)
			(unlocked yes)
			(layer "F.Fab")
			(effects
				(font
					(size 1.905 1.4224)
					(thickness 0.1524)
				)
				(justify left)
			)
		)
		(pad "A" smd rect
			(at -0.750062 0)
			(size 0.8128 0.8128)
			(layers "F.Cu" "F.Mask" "F.Paste")
			(net "LED_CPU_RMCA_CATERR")
		)
		(pad "C" smd rect
			(at 0.750062 0)
			(size 0.8128 0.8128)
			(layers "F.Cu" "F.Mask" "F.Paste")
			(net "GND")
		)
	)
	(footprint ""
		(layer "F.Cu")
		(at 393.75461 -402.371052 -90)
		(property "Reference" "C948"
			(at 0 0 270)
			(layer "F.SilkS")
			(hide yes)
			(effects
				(font
					(size 1.27 1.27)
				)
			)
		)
		(property "Value" ""
			(at 0 0 270)
			(layer "F.Fab")
			(effects
				(font
					(size 1.27 1.27)
				)
			)
		)
		(duplicate_pad_numbers_are_jumpers no)
		(fp_line
			(start -0.299974 0.150114)
			(end -0.299974 -0.150114)
			(stroke
				(width 0.1)
				(type default)
			)
			(layer "F.Fab")
		)
		(fp_line
			(start 0.299974 0.150114)
			(end -0.299974 0.150114)
			(stroke
				(width 0.1)
				(type default)
			)
			(layer "F.Fab")
		)
		(fp_line
			(start -0.299974 -0.150114)
			(end 0.299974 -0.150114)
			(stroke
				(width 0.1)
				(type default)
			)
			(layer "F.Fab")
		)
		(fp_line
			(start 0.299974 -0.150114)
			(end 0.299974 0.150114)
			(stroke
				(width 0.1)
				(type default)
			)
			(layer "F.Fab")
		)
		(pad "1" smd rect
			(at -0.2667 0 270)
			(size 0.3048 0.381)
			(layers "F.Cu" "F.Mask" "F.Paste")
			(net "P5E_CPU0_PE2_TX_C_DN<8>")
		)
		(pad "2" smd rect
			(at 0.2667 0 270)
			(size 0.3048 0.381)
			(layers "F.Cu" "F.Mask" "F.Paste")
			(net "P5E_CPU0_PE2_TX_DN<8>")
		)
	)
	(footprint ""
		(layer "F.Cu")
		(at 113.44656 -28.567634 90)
		(property "Reference" "U218"
			(at -0.191516 -5.00888 0)
			(unlocked yes)
			(layer "F.SilkS")
			(effects
				(font
					(size 0.7874 0.5842)
					(thickness 0.1524)
				)
				(justify left)
			)
		)
		(property "Value" ""
			(at 0 0 90)
			(layer "F.Fab")
			(effects
				(font
					(size 1.27 1.27)
				)
			)
		)
		(duplicate_pad_numbers_are_jumpers no)
		(fp_line
			(start 1.733296 -1.549908)
			(end 0.660908 -1.549908)
			(stroke
				(width 0.1524)
				(type default)
			)
			(layer "F.SilkS")
		)
		(fp_line
			(start 0.660908 -1.549908)
			(end 0 -0.889)
			(stroke
				(width 0.1524)
				(type default)
			)
			(layer "F.SilkS")
		)
		(fp_line
			(start -0.660908 -1.549908)
			(end -1.733296 -1.549908)
			(stroke
				(width 0.1524)
				(type default)
			)
			(layer "F.SilkS")
		)
		(fp_line
			(start -1.733296 -1.549908)
			(end -1.733296 1.549908)
			(stroke
				(width 0.1524)
				(type default)
			)
			(layer "F.SilkS")
		)
		(fp_line
			(start 0 -0.889)
			(end -0.660908 -1.549908)
			(stroke
				(width 0.1524)
				(type default)
			)
			(layer "F.SilkS")
		)
		(fp_line
			(start 1.733296 1.549908)
			(end 1.733296 -1.549908)
			(stroke
				(width 0.1524)
				(type default)
			)
			(layer "F.SilkS")
		)
		(fp_line
			(start -1.733296 1.549908)
			(end 1.733296 1.549908)
			(stroke
				(width 0.1524)
				(type default)
			)
			(layer "F.SilkS")
		)
		(fp_poly
			(pts
				(xy -0.982726 -2.387854) (xy -1.236726 -1.879854) (xy -1.490726 -2.387854)
			)
			(stroke
				(width 0)
				(type default)
			)
			(fill yes)
			(layer "F.SilkS")
		)
		(fp_line
			(start 0.849884 -1.549908)
			(end -0.849884 -1.549908)
			(stroke
				(width 0.1)
				(type default)
			)
			(layer "F.Fab")
		)
		(fp_line
			(start -0.849884 -1.549908)
			(end -0.849884 1.549908)
			(stroke
				(width 0.1)
				(type default)
			)
			(layer "F.Fab")
		)
		(fp_line
			(start 0.849884 1.549908)
			(end 0.849884 -1.549908)
			(stroke
				(width 0.1)
				(type default)
			)
			(layer "F.Fab")
		)
		(fp_line
			(start -0.849884 1.549908)
			(end 0.849884 1.549908)
			(stroke
				(width 0.1)
				(type default)
			)
			(layer "F.Fab")
		)
		(fp_poly
			(pts
				(xy -2.4384 -1.20396) (xy -2.4384 -0.69596) (xy -1.9304 -0.94996)
			)
			(stroke
				(width 0)
				(type default)
			)
			(fill yes)
			(layer "F.Fab")
		)
		(pad "1" smd rect
			(at -1.199896 -0.94996)
			(size 0.5588 0.8128)
			(layers "F.Cu" "F.Mask" "F.Paste")
			(net "NC_U218_NC1")
		)
		(pad "2" smd rect
			(at -1.199896 0)
			(size 0.5588 0.8128)
			(layers "F.Cu" "F.Mask" "F.Paste")
			(net "FM_SYS_THROTTLE_R_N")
		)
		(pad "3" smd rect
			(at -1.199896 0.94996)
			(size 0.5588 0.8128)
			(layers "F.Cu" "F.Mask" "F.Paste")
			(net "GND")
		)
		(pad "4" smd rect
			(at 1.199896 0.94996)
			(size 0.5588 0.8128)
			(layers "F.Cu" "F.Mask" "F.Paste")
			(net "OCP_V3_2_PWRBRK_BUFF_N")
		)
		(pad "5" smd rect
			(at 1.199896 -0.94996)
			(size 0.5588 0.8128)
			(layers "F.Cu" "F.Mask" "F.Paste")
			(net "P3V3_AUX")
		)
	)
	(footprint ""
		(layer "F.Cu")
		(at 314.490608 -408.517344 -90)
		(property "Reference" "C908"
			(at 0 0 270)
			(layer "F.SilkS")
			(hide yes)
			(effects
				(font
					(size 1.27 1.27)
				)
			)
		)
		(property "Value" ""
			(at 0 0 270)
			(layer "F.Fab")
			(effects
				(font
					(size 1.27 1.27)
				)
			)
		)
		(duplicate_pad_numbers_are_jumpers no)
		(fp_line
			(start -0.299974 0.150114)
			(end -0.299974 -0.150114)
			(stroke
				(width 0.1)
				(type default)
			)
			(layer "F.Fab")
		)
		(fp_line
			(start 0.299974 0.150114)
			(end -0.299974 0.150114)
			(stroke
				(width 0.1)
				(type default)
			)
			(layer "F.Fab")
		)
		(fp_line
			(start -0.299974 -0.150114)
			(end 0.299974 -0.150114)
			(stroke
				(width 0.1)
				(type default)
			)
			(layer "F.Fab")
		)
		(fp_line
			(start 0.299974 -0.150114)
			(end 0.299974 0.150114)
			(stroke
				(width 0.1)
				(type default)
			)
			(layer "F.Fab")
		)
		(pad "1" smd rect
			(at -0.2667 0 270)
			(size 0.3048 0.381)
			(layers "F.Cu" "F.Mask" "F.Paste")
			(net "P5E_CPU0_PE0_TX_C_DN<12>")
		)
		(pad "2" smd rect
			(at 0.2667 0 270)
			(size 0.3048 0.381)
			(layers "F.Cu" "F.Mask" "F.Paste")
			(net "P5E_CPU0_PE0_TX_DN<12>")
		)
	)
	(footprint ""
		(layer "F.Cu")
		(at 161.21888 -133.695948 180)
		(property "Reference" "R2486"
			(at 0 0 180)
			(layer "F.SilkS")
			(hide yes)
			(effects
				(font
					(size 1.27 1.27)
				)
			)
		)
		(property "Value" ""
			(at 0 0 180)
			(layer "F.Fab")
			(effects
				(font
					(size 1.27 1.27)
				)
			)
		)
		(duplicate_pad_numbers_are_jumpers no)
		(fp_line
			(start 0.7874 0.4064)
			(end -0.7874 0.4064)
			(stroke
				(width 0.1524)
				(type default)
			)
			(layer "F.SilkS")
		)
		(fp_line
			(start 0.7874 -0.4064)
			(end 0.7874 0.4064)
			(stroke
				(width 0.1524)
				(type default)
			)
			(layer "F.SilkS")
		)
		(fp_line
			(start -0.7874 0.4064)
			(end -0.7874 -0.4064)
			(stroke
				(width 0.1524)
				(type default)
			)
			(layer "F.SilkS")
		)
		(fp_line
			(start -0.7874 -0.4064)
			(end 0.7874 -0.4064)
			(stroke
				(width 0.1524)
				(type default)
			)
			(layer "F.SilkS")
		)
		(fp_line
			(start 0.67945 0.3048)
			(end 0.120396 0.3048)
			(stroke
				(width 0.1)
				(type default)
			)
			(layer "F.Fab")
		)
		(fp_line
			(start 0.67945 -0.3048)
			(end 0.67945 0.3048)
			(stroke
				(width 0.1)
				(type default)
			)
			(layer "F.Fab")
		)
		(fp_line
			(start 0.12065 -0.2794)
			(end 0.12065 -0.3048)
			(stroke
				(width 0.1)
				(type default)
			)
			(layer "F.Fab")
		)
		(fp_line
			(start 0.12065 -0.3048)
			(end 0.67945 -0.3048)
			(stroke
				(width 0.1)
				(type default)
			)
			(layer "F.Fab")
		)
		(fp_line
			(start 0.120396 0.3048)
			(end 0.120396 0.2794)
			(stroke
				(width 0.1)
				(type default)
			)
			(layer "F.Fab")
		)
		(fp_line
			(start 0.120396 0.2794)
			(end -0.12065 0.2794)
			(stroke
				(width 0.1)
				(type default)
			)
			(layer "F.Fab")
		)
		(fp_line
			(start -0.12065 0.3048)
			(end -0.67945 0.3048)
			(stroke
				(width 0.1)
				(type default)
			)
			(layer "F.Fab")
		)
		(fp_line
			(start -0.12065 0.2794)
			(end -0.12065 0.3048)
			(stroke
				(width 0.1)
				(type default)
			)
			(layer "F.Fab")
		)
		(fp_line
			(start -0.12065 -0.2794)
			(end 0.12065 -0.2794)
			(stroke
				(width 0.1)
				(type default)
			)
			(layer "F.Fab")
		)
		(fp_line
			(start -0.12065 -0.305054)
			(end -0.12065 -0.2794)
			(stroke
				(width 0.1)
				(type default)
			)
			(layer "F.Fab")
		)
		(fp_line
			(start -0.67945 0.3048)
			(end -0.67945 -0.305054)
			(stroke
				(width 0.1)
				(type default)
			)
			(layer "F.Fab")
		)
		(fp_line
			(start -0.67945 -0.305054)
			(end -0.12065 -0.305054)
			(stroke
				(width 0.1)
				(type default)
			)
			(layer "F.Fab")
		)
		(pad "1" smd circle
			(at -0.40005 0 180)
			(size 0 0)
			(layers "F.Cu" "F.Mask" "F.Paste")
			(net "P3V3_AUX")
		)
		(pad "2" smd circle
			(at 0.40005 0 180)
			(size 0 0)
			(layers "F.Cu" "F.Mask" "F.Paste")
			(net "PWRGD_P3V3_AUX_R2")
		)
	)
	(footprint ""
		(layer "F.Cu")
		(at 170.23588 -435.955948)
		(property "Reference" "R3392"
			(at 0 0 0)
			(layer "F.SilkS")
			(hide yes)
			(effects
				(font
					(size 1.27 1.27)
				)
			)
		)
		(property "Value" ""
			(at 0 0 0)
			(layer "F.Fab")
			(effects
				(font
					(size 1.27 1.27)
				)
			)
		)
		(duplicate_pad_numbers_are_jumpers no)
		(fp_line
			(start -0.7874 -0.4064)
			(end 0.7874 -0.4064)
			(stroke
				(width 0.1524)
				(type default)
			)
			(layer "F.SilkS")
		)
		(fp_line
			(start -0.7874 0.4064)
			(end -0.7874 -0.4064)
			(stroke
				(width 0.1524)
				(type default)
			)
			(layer "F.SilkS")
		)
		(fp_line
			(start 0.7874 -0.4064)
			(end 0.7874 0.4064)
			(stroke
				(width 0.1524)
				(type default)
			)
			(layer "F.SilkS")
		)
		(fp_line
			(start 0.7874 0.4064)
			(end -0.7874 0.4064)
			(stroke
				(width 0.1524)
				(type default)
			)
			(layer "F.SilkS")
		)
		(fp_line
			(start -0.67945 -0.305054)
			(end -0.12065 -0.305054)
			(stroke
				(width 0.1)
				(type default)
			)
			(layer "F.Fab")
		)
		(fp_line
			(start -0.67945 0.3048)
			(end -0.67945 -0.305054)
			(stroke
				(width 0.1)
				(type default)
			)
			(layer "F.Fab")
		)
		(fp_line
			(start -0.12065 -0.305054)
			(end -0.12065 -0.2794)
			(stroke
				(width 0.1)
				(type default)
			)
			(layer "F.Fab")
		)
		(fp_line
			(start -0.12065 -0.2794)
			(end 0.12065 -0.2794)
			(stroke
				(width 0.1)
				(type default)
			)
			(layer "F.Fab")
		)
		(fp_line
			(start -0.12065 0.2794)
			(end -0.12065 0.3048)
			(stroke
				(width 0.1)
				(type default)
			)
			(layer "F.Fab")
		)
		(fp_line
			(start -0.12065 0.3048)
			(end -0.67945 0.3048)
			(stroke
				(width 0.1)
				(type default)
			)
			(layer "F.Fab")
		)
		(fp_line
			(start 0.120396 0.2794)
			(end -0.12065 0.2794)
			(stroke
				(width 0.1)
				(type default)
			)
			(layer "F.Fab")
		)
		(fp_line
			(start 0.120396 0.3048)
			(end 0.120396 0.2794)
			(stroke
				(width 0.1)
				(type default)
			)
			(layer "F.Fab")
		)
		(fp_line
			(start 0.12065 -0.3048)
			(end 0.67945 -0.3048)
			(stroke
				(width 0.1)
				(type default)
			)
			(layer "F.Fab")
		)
		(fp_line
			(start 0.12065 -0.2794)
			(end 0.12065 -0.3048)
			(stroke
				(width 0.1)
				(type default)
			)
			(layer "F.Fab")
		)
		(fp_line
			(start 0.67945 -0.3048)
			(end 0.67945 0.3048)
			(stroke
				(width 0.1)
				(type default)
			)
			(layer "F.Fab")
		)
		(fp_line
			(start 0.67945 0.3048)
			(end 0.120396 0.3048)
			(stroke
				(width 0.1)
				(type default)
			)
			(layer "F.Fab")
		)
		(pad "1" smd circle
			(at -0.40005 0)
			(size 0 0)
			(layers "F.Cu" "F.Mask" "F.Paste")
			(net "GPU_BASE_STBY_EN_BUF_R")
		)
		(pad "2" smd circle
			(at 0.40005 0)
			(size 0 0)
			(layers "F.Cu" "F.Mask" "F.Paste")
			(net "GPU_BASE_STBY_EN_BUF")
		)
	)
	(footprint ""
		(layer "F.Cu")
		(at 448.672458 -92.493592 180)
		(property "Reference" "R3616"
			(at 0 0 180)
			(layer "F.SilkS")
			(hide yes)
			(effects
				(font
					(size 1.27 1.27)
				)
			)
		)
		(property "Value" ""
			(at 0 0 180)
			(layer "F.Fab")
			(effects
				(font
					(size 1.27 1.27)
				)
			)
		)
		(duplicate_pad_numbers_are_jumpers no)
		(fp_line
			(start 0.7874 0.4064)
			(end -0.7874 0.4064)
			(stroke
				(width 0.1524)
				(type default)
			)
			(layer "F.SilkS")
		)
		(fp_line
			(start 0.7874 -0.4064)
			(end 0.7874 0.4064)
			(stroke
				(width 0.1524)
				(type default)
			)
			(layer "F.SilkS")
		)
		(fp_line
			(start -0.7874 0.4064)
			(end -0.7874 -0.4064)
			(stroke
				(width 0.1524)
				(type default)
			)
			(layer "F.SilkS")
		)
		(fp_line
			(start -0.7874 -0.4064)
			(end 0.7874 -0.4064)
			(stroke
				(width 0.1524)
				(type default)
			)
			(layer "F.SilkS")
		)
		(fp_line
			(start 0.67945 0.3048)
			(end 0.120396 0.3048)
			(stroke
				(width 0.1)
				(type default)
			)
			(layer "F.Fab")
		)
		(fp_line
			(start 0.67945 -0.3048)
			(end 0.67945 0.3048)
			(stroke
				(width 0.1)
				(type default)
			)
			(layer "F.Fab")
		)
		(fp_line
			(start 0.12065 -0.2794)
			(end 0.12065 -0.3048)
			(stroke
				(width 0.1)
				(type default)
			)
			(layer "F.Fab")
		)
		(fp_line
			(start 0.12065 -0.3048)
			(end 0.67945 -0.3048)
			(stroke
				(width 0.1)
				(type default)
			)
			(layer "F.Fab")
		)
		(fp_line
			(start 0.120396 0.3048)
			(end 0.120396 0.2794)
			(stroke
				(width 0.1)
				(type default)
			)
			(layer "F.Fab")
		)
		(fp_line
			(start 0.120396 0.2794)
			(end -0.12065 0.2794)
			(stroke
				(width 0.1)
				(type default)
			)
			(layer "F.Fab")
		)
		(fp_line
			(start -0.12065 0.3048)
			(end -0.67945 0.3048)
			(stroke
				(width 0.1)
				(type default)
			)
			(layer "F.Fab")
		)
		(fp_line
			(start -0.12065 0.2794)
			(end -0.12065 0.3048)
			(stroke
				(width 0.1)
				(type default)
			)
			(layer "F.Fab")
		)
		(fp_line
			(start -0.12065 -0.2794)
			(end 0.12065 -0.2794)
			(stroke
				(width 0.1)
				(type default)
			)
			(layer "F.Fab")
		)
		(fp_line
			(start -0.12065 -0.305054)
			(end -0.12065 -0.2794)
			(stroke
				(width 0.1)
				(type default)
			)
			(layer "F.Fab")
		)
		(fp_line
			(start -0.67945 0.3048)
			(end -0.67945 -0.305054)
			(stroke
				(width 0.1)
				(type default)
			)
			(layer "F.Fab")
		)
		(fp_line
			(start -0.67945 -0.305054)
			(end -0.12065 -0.305054)
			(stroke
				(width 0.1)
				(type default)
			)
			(layer "F.Fab")
		)
		(pad "1" smd circle
			(at -0.40005 0 180)
			(size 0 0)
			(layers "F.Cu" "F.Mask" "F.Paste")
			(net "GND")
		)
		(pad "2" smd circle
			(at 0.40005 0 180)
			(size 0 0)
			(layers "F.Cu" "F.Mask" "F.Paste")
			(net "INA230_1_A1")
		)
	)
)
